# BASEBOARD_FAB2 (Tioga Pass) — schematic netlist excerpt (pin names and nets, part order shuffled) for the footprints in the layout excerpt that follows; sources: Cadence DE-HDL packaged netlist, KiCad conversion of Wiwynn_Tioga_Pass_MB.brd

C8A6  CAP  10UF 6.3V 20% X6S  pkg 0603  page 237 : A = P3V3_STBY ; B = GND
C2D1  CAP_A  22.0UF 4V 20% X6S  pkg 0603V  page 228 : A = PVDDQ_KLM ; B = GND
C834  CAP  0.22UF 16V 10% X7R  pkg 0402  page 244 : A = P3E_CPU0_PE1_PCH_TXN<10> ; B = P3E_CPU0_PE1_PCH_CON_TXN<10>

(kicad_pcb
	(version 20260206)
	(generator "pcbnew")
	(generator_version "10.0")
	(general
		(thickness 1.6)
		(legacy_teardrops no)
	)
	(paper "A4")
	(title_block
		(title "Wiwynn_Tioga_Pass_MB.brd")
		(comment 1 "Tioga Pass / footprints 197-199 of 4770")
	)
	(layers
		(0 "F.Cu" signal "TOP")
		(4 "In1.Cu" signal "L2GND")
		(6 "In2.Cu" signal "L3")
		(8 "In3.Cu" signal "L4GND")
		(10 "In4.Cu" signal "L5")
		(12 "In5.Cu" signal "L6GND")
		(14 "In6.Cu" signal "L7VCC")
		(16 "In7.Cu" signal "L8VCC")
		(18 "In8.Cu" signal "L9GND")
		(20 "In9.Cu" signal "L10")
		(22 "In10.Cu" signal "L11GND")
		(24 "In11.Cu" signal "L12")
		(26 "In12.Cu" signal "L13GND")
		(2 "B.Cu" signal "BOTTOM")
		(9 "F.Adhes" user "F.Adhesive")
		(11 "B.Adhes" user "B.Adhesive")
		(13 "F.Paste" user "Package Geometry/Pastemask Top")
		(15 "B.Paste" user "Package Geometry/Pastemask Bottom")
		(5 "F.SilkS" user "Ref Des/Silkscreen Top")
		(7 "B.SilkS" user "Ref Des/Silkscreen Bottom")
		(1 "F.Mask" user "Board Geometry/Soldermask Top")
		(3 "B.Mask" user "Board Geometry/Soldermask Bottom")
		(17 "Dwgs.User" user "User.Drawings")
		(19 "Cmts.User" user "User.Comments")
		(21 "Eco1.User" user "User.Eco1")
		(23 "Eco2.User" user "User.Eco2")
		(25 "Edge.Cuts" user "Board Geometry/Outline")
		(27 "Margin" user)
		(31 "F.CrtYd" user "Package Geometry/Place Bound Top")
		(29 "B.CrtYd" user "Package Geometry/Place Bound Bottom")
		(35 "F.Fab" user "Ref Des/Assembly Top")
		(33 "B.Fab" user "Ref Des/Assembly Bottom")
	)
	(footprint ""
		(layer "F.Cu")
		(at 402.336 -152.527 180)
		(property "Reference" "C8A6"
			(at 0 0 180)
			(layer "F.SilkS")
			(hide yes)
			(effects
				(font
					(size 1.27 1.27)
				)
			)
		)
		(property "Value" ""
			(at 0 0 180)
			(layer "F.Fab")
			(effects
				(font
					(size 1.27 1.27)
				)
			)
		)
		(duplicate_pad_numbers_are_jumpers no)
		(fp_poly
			(pts
				(xy -0.4953 -0.2032) (xy 0.4953 -0.2032) (xy 0.4953 1.6002) (xy -0.4953 1.6002)
			)
			(stroke
				(width 0)
				(type default)
			)
			(fill no)
			(layer "F.CrtYd")
		)
		(fp_line
			(start 0.4953 1.6002)
			(end -0.4953 1.6002)
			(stroke
				(width 0.1)
				(type default)
			)
			(layer "F.Fab")
		)
		(fp_line
			(start 0.4953 -0.2032)
			(end 0.4953 1.6002)
			(stroke
				(width 0.1)
				(type default)
			)
			(layer "F.Fab")
		)
		(fp_line
			(start -0.4953 1.6002)
			(end -0.4953 -0.2032)
			(stroke
				(width 0.1)
				(type default)
			)
			(layer "F.Fab")
		)
		(fp_line
			(start -0.4953 -0.2032)
			(end 0.4953 -0.2032)
			(stroke
				(width 0.1)
				(type default)
			)
			(layer "F.Fab")
		)
		(pad "1" smd rect
			(at 0 0 180)
			(size 0.762 0.889)
			(layers "F.Cu" "F.Mask" "F.Paste")
			(net "P3V3_STBY")
		)
		(pad "2" smd rect
			(at 0 1.397 180)
			(size 0.762 0.889)
			(layers "F.Cu" "F.Mask" "F.Paste")
			(net "GND")
		)
		(zone
			(layer "F.Cu")
			(hatch none 0.5)
			(connect_pads
				(clearance 0)
			)
			(min_thickness 0.25)
			(keepout
				(tracks not_allowed)
				(vias allowed)
				(pads allowed)
				(copperpour not_allowed)
				(footprints allowed)
			)
			(placement
				(enabled no)
				(sheetname "")
			)
			(fill
				(thermal_gap 0.5)
				(thermal_bridge_width 0.5)
				(island_removal_mode 0)
			)
			(polygon
				(pts
					(xy 402.717 -152.9715) (xy 401.955 -152.9715) (xy 401.955 -153.4795) (xy 402.717 -153.4795)
				)
			)
		)
	)
	(footprint ""
		(layer "F.Cu")
		(at 337.404202 -121.282968 -90)
		(property "Reference" "C834"
			(at -0.8382 -0.67818 270)
			(unlocked yes)
			(layer "F.SilkS")
			(effects
				(font
					(size 0.4064 0.254)
					(thickness 0.1524)
				)
				(justify left)
			)
		)
		(property "Value" ""
			(at 0 0 270)
			(layer "F.Fab")
			(effects
				(font
					(size 1.27 1.27)
				)
			)
		)
		(duplicate_pad_numbers_are_jumpers no)
		(fp_poly
			(pts
				(xy 0.3048 -0.1016) (xy 0.3048 0.9906) (xy -0.3048 0.9906) (xy -0.3048 -0.1016)
			)
			(stroke
				(width 0)
				(type default)
			)
			(fill no)
			(layer "F.CrtYd")
		)
		(fp_line
			(start -0.3048 0.9906)
			(end 0.3048 0.9906)
			(stroke
				(width 0.1)
				(type default)
			)
			(layer "F.Fab")
		)
		(fp_line
			(start 0.3048 0.9906)
			(end 0.3048 -0.1016)
			(stroke
				(width 0.1)
				(type default)
			)
			(layer "F.Fab")
		)
		(fp_line
			(start -0.3048 -0.1016)
			(end -0.3048 0.9906)
			(stroke
				(width 0.1)
				(type default)
			)
			(layer "F.Fab")
		)
		(fp_line
			(start 0.3048 -0.1016)
			(end -0.3048 -0.1016)
			(stroke
				(width 0.1)
				(type default)
			)
			(layer "F.Fab")
		)
		(pad "1" smd rect
			(at 0 0 270)
			(size 0.508 0.508)
			(layers "F.Cu" "F.Mask" "F.Paste")
			(net "P3E_CPU0_PE1_PCH_TXN<10>")
		)
		(pad "2" smd rect
			(at 0 0.889 270)
			(size 0.508 0.508)
			(layers "F.Cu" "F.Mask" "F.Paste")
			(net "P3E_CPU0_PE1_PCH_CON_TXN<10>")
		)
		(zone
			(layer "F.Cu")
			(hatch none 0.5)
			(connect_pads
				(clearance 0)
			)
			(min_thickness 0.25)
			(keepout
				(tracks not_allowed)
				(vias allowed)
				(pads allowed)
				(copperpour not_allowed)
				(footprints allowed)
			)
			(placement
				(enabled no)
				(sheetname "")
			)
			(fill
				(thermal_gap 0.5)
				(thermal_bridge_width 0.5)
				(island_removal_mode 0)
			)
			(polygon
				(pts
					(xy 336.769202 -121.536968) (xy 336.769202 -121.028968) (xy 337.150202 -121.028968) (xy 337.150202 -121.536968)
				)
			)
		)
		(zone
			(layer "F.Cu")
			(hatch none 0.5)
			(connect_pads
				(clearance 0)
			)
			(min_thickness 0.25)
			(keepout
				(tracks allowed)
				(vias not_allowed)
				(pads allowed)
				(copperpour not_allowed)
				(footprints allowed)
			)
			(placement
				(enabled no)
				(sheetname "")
			)
			(fill
				(thermal_gap 0.5)
				(thermal_bridge_width 0.5)
				(island_removal_mode 0)
			)
			(polygon
				(pts
					(xy 337.150202 -121.536968) (xy 337.150202 -121.028968) (xy 336.769202 -121.028968) (xy 336.769202 -121.536968)
				)
			)
		)
	)
	(footprint ""
		(layer "F.Cu")
		(at 103.506778 -84.890102)
		(property "Reference" "C2D1"
			(at 0 0 0)
			(layer "F.SilkS")
			(hide yes)
			(effects
				(font
					(size 1.27 1.27)
				)
			)
		)
		(property "Value" ""
			(at 0 0 0)
			(layer "F.Fab")
			(effects
				(font
					(size 1.27 1.27)
				)
			)
		)
		(duplicate_pad_numbers_are_jumpers no)
		(fp_poly
			(pts
				(xy -0.4953 -0.2032) (xy 0.4953 -0.2032) (xy 0.4953 1.6002) (xy -0.4953 1.6002)
			)
			(stroke
				(width 0)
				(type default)
			)
			(fill no)
			(layer "F.CrtYd")
		)
		(fp_line
			(start -0.4953 -0.2032)
			(end 0.4953 -0.2032)
			(stroke
				(width 0.1)
				(type default)
			)
			(layer "F.Fab")
		)
		(fp_line
			(start -0.4953 1.6002)
			(end -0.4953 -0.2032)
			(stroke
				(width 0.1)
				(type default)
			)
			(layer "F.Fab")
		)
		(fp_line
			(start 0.4953 -0.2032)
			(end 0.4953 1.6002)
			(stroke
				(width 0.1)
				(type default)
			)
			(layer "F.Fab")
		)
		(fp_line
			(start 0.4953 1.6002)
			(end -0.4953 1.6002)
			(stroke
				(width 0.1)
				(type default)
			)
			(layer "F.Fab")
		)
		(pad "1" smd rect
			(at 0 0)
			(size 0.762 0.889)
			(layers "F.Cu" "F.Mask" "F.Paste")
			(net "PVDDQ_KLM")
		)
		(pad "2" smd rect
			(at 0 1.397)
			(size 0.762 0.889)
			(layers "F.Cu" "F.Mask" "F.Paste")
			(net "GND")
		)
		(zone
			(layer "F.Cu")
			(hatch none 0.5)
			(connect_pads
				(clearance 0)
			)
			(min_thickness 0.25)
			(keepout
				(tracks not_allowed)
				(vias allowed)
				(pads allowed)
				(copperpour not_allowed)
				(footprints allowed)
			)
			(placement
				(enabled no)
				(sheetname "")
			)
			(fill
				(thermal_gap 0.5)
				(thermal_bridge_width 0.5)
				(island_removal_mode 0)
			)
			(polygon
				(pts
					(xy 103.125778 -84.445602) (xy 103.887778 -84.445602) (xy 103.887778 -83.937602) (xy 103.125778 -83.937602)
				)
			)
		)
	)
)
